FILE_TYPE = CONNECTIVITY;
{Allegro Design Entry HDL 17.4-2019 S026 (4007227) 1/17/2022}
"PAGE_NUMBER" = 395;
0"NC";
1"P5E_CPU1_P1_RX_DP<15:8>";
2"P5E_CPU1_P1_RX_DP<7:0>";
3"P5E_CPU1_P1_RX_DN<15:8>";
4"P5E_CPU1_P1_RX_DN<7:0>";
5"P5E_CPU1_P1_RX_DP<15>";
6"P5E_CPU1_P1_RX_DN<14>";
7"P5E_CPU1_P1_RX_DP<14>";
8"P5E_CPU1_P1_RX_DN<15>";
9"P5E_CPU1_P1_RX_DN<1>";
10"P5E_CPU1_P1_RX_DN<2>";
11"P5E_CPU1_P1_RX_DN<3>";
12"P5E_CPU1_P1_RX_DN<4>";
13"P5E_CPU1_P1_RX_DN<5>";
14"P5E_CPU1_P1_RX_DN<7>";
15"P5E_CPU1_P1_RX_DN<0>";
16"P5E_CPU1_P1_RX_DN<6>";
17"P5E_CPU1_P1_RX_DN<11>";
18"P5E_CPU1_P1_RX_DN<10>";
19"P5E_CPU1_P1_RX_DN<8>";
20"P5E_CPU1_P1_RX_DN<9>";
21"P5E_CPU1_P1_RX_DN<13>";
22"P5E_CPU1_P1_RX_DN<12>";
23"P5E_CPU1_P1_RX_DP<3>";
24"P5E_CPU1_P1_RX_DP<4>";
25"P5E_CPU1_P1_RX_DP<5>";
26"P5E_CPU1_P1_RX_DP<0>";
27"P5E_CPU1_P1_RX_DP<1>";
28"P5E_CPU1_P1_RX_DP<6>";
29"P5E_CPU1_P1_RX_DP<2>";
30"P5E_CPU1_P1_RX_DP<7>";
31"P5E_CPU1_P1_RX_DP<10>";
32"P5E_CPU1_P1_RX_DP<9>";
33"P5E_CPU1_P1_RX_DP<8>";
34"P5E_CPU1_P1_RX_DP<11>";
35"P5E_CPU1_P1_RX_DP<13>";
36"P5E_CPU1_P1_RX_DP<12>";
%"PT5161LRS"
"6","(-7450,4425)","0","pure_quanta","I1";
;
LOCATION"U6015"
$SEC"6"
CDS_SEC"6"
VALUE"PT5161LRS"
MATERIAL"IC"
PART_TYPE"SMLF"
CDS_LIB"pure_quanta"
CDS_LMAN_SYM_OUTLINE"-350,1450,300,-1400"
NEEDS_NO_SIZE"TRUE"
PART_NUMBER"AJ051610U03";
"A_PETN7"
$PN"CC29"19;
"A_PETP7"
$PN"CA26"33;
"A_PETN6"
$PN"BT29"20;
"A_PETP6"
$PN"BP26"32;
"A_PETN5"
$PN"BJ29"18;
"A_PETP5"
$PN"BG26"31;
"A_PETN4"
$PN"BB29"17;
"A_PETP4"
$PN"AY26"34;
"A_PETN3"
$PN"AR29"22;
"A_PETP3"
$PN"AN26"36;
"A_PETN2"
$PN"AH29"21;
"A_PETP2"
$PN"AF26"35;
"A_PETN1"
$PN"AA29"6;
"A_PETP1"
$PN"W26"7;
"A_PETN0"
$PN"P29"8;
"A_PETP0"
$PN"M26"5;
%"TAP"
"1","(-6425,5325)","0","standard","I10";
;
CDS_LIB"standard"
BODY_TYPE"PLUMBING"
HDL_TAP"TRUE";
"B \NAC \NWC"1;
"S \NAC"
BN"14"7;
%"TAP"
"1","(-6425,4975)","0","standard","I11";
;
CDS_LIB"standard"
BODY_TYPE"PLUMBING"
HDL_TAP"TRUE";
"B \NAC \NWC"1;
"S \NAC"
BN"13"35;
%"TAP"
"1","(-6425,4625)","0","standard","I12";
;
CDS_LIB"standard"
BODY_TYPE"PLUMBING"
HDL_TAP"TRUE";
"B \NAC \NWC"1;
"S \NAC"
BN"12"36;
%"TAP"
"1","(-6225,4525)","0","standard","I13";
;
CDS_LIB"standard"
BODY_TYPE"PLUMBING"
HDL_TAP"TRUE";
"B \NAC \NWC"3;
"S \NAC"
BN"12"22;
%"TAP"
"1","(-6225,4875)","0","standard","I14";
;
CDS_LIB"standard"
BODY_TYPE"PLUMBING"
HDL_TAP"TRUE";
"B \NAC \NWC"3;
"S \NAC"
BN"13"21;
%"TAP"
"1","(-6225,5225)","0","standard","I15";
;
CDS_LIB"standard"
BODY_TYPE"PLUMBING"
HDL_TAP"TRUE";
"B \NAC \NWC"3;
"S \NAC"
BN"14"6;
%"TAP"
"1","(-6425,5675)","0","standard","I16";
;
CDS_LIB"standard"
BODY_TYPE"PLUMBING"
HDL_TAP"TRUE";
"B \NAC \NWC"1;
"S \NAC"
BN"15"5;
%"TAP"
"1","(-6225,5575)","0","standard","I17";
;
CDS_LIB"standard"
BODY_TYPE"PLUMBING"
HDL_TAP"TRUE";
"B \NAC \NWC"3;
"S \NAC"
BN"15"8;
%"TAP"
"1","(-6425,3225)","0","standard","I2";
;
CDS_LIB"standard"
BODY_TYPE"PLUMBING"
HDL_TAP"TRUE";
"B \NAC \NWC"1;
"S \NAC"
BN"8"33;
%"TAP"
"1","(-1900,3300)","0","standard","I20";
;
CDS_LIB"standard"
BODY_TYPE"PLUMBING"
HDL_TAP"TRUE";
"B \NAC \NWC"2;
"S \NAC"
BN"0"26;
%"TAP"
"1","(-1900,3650)","0","standard","I21";
;
CDS_LIB"standard"
BODY_TYPE"PLUMBING"
HDL_TAP"TRUE";
"B \NAC \NWC"2;
"S \NAC"
BN"1"27;
%"TAP"
"1","(-1900,4000)","0","standard","I22";
;
CDS_LIB"standard"
BODY_TYPE"PLUMBING"
HDL_TAP"TRUE";
"B \NAC \NWC"2;
"S \NAC"
BN"2"29;
%"TAP"
"1","(-1900,4350)","0","standard","I23";
;
CDS_LIB"standard"
BODY_TYPE"PLUMBING"
HDL_TAP"TRUE";
"B \NAC \NWC"2;
"S \NAC"
BN"3"23;
%"TAP"
"1","(-1700,3200)","0","standard","I24";
;
CDS_LIB"standard"
BODY_TYPE"PLUMBING"
HDL_TAP"TRUE";
"B \NAC \NWC"4;
"S \NAC"
BN"0"15;
%"TAP"
"1","(-1700,3550)","0","standard","I25";
;
CDS_LIB"standard"
BODY_TYPE"PLUMBING"
HDL_TAP"TRUE";
"B \NAC \NWC"4;
"S \NAC"
BN"1"9;
%"TAP"
"1","(-1700,3900)","0","standard","I26";
;
CDS_LIB"standard"
BODY_TYPE"PLUMBING"
HDL_TAP"TRUE";
"B \NAC \NWC"4;
"S \NAC"
BN"2"10;
%"TAP"
"1","(-1700,4250)","0","standard","I27";
;
CDS_LIB"standard"
BODY_TYPE"PLUMBING"
HDL_TAP"TRUE";
"B \NAC \NWC"4;
"S \NAC"
BN"3"11;
%"TAP"
"1","(-1900,4700)","0","standard","I28";
;
CDS_LIB"standard"
BODY_TYPE"PLUMBING"
HDL_TAP"TRUE";
"B \NAC \NWC"2;
"S \NAC"
BN"4"24;
%"TAP"
"1","(-1900,5050)","0","standard","I29";
;
CDS_LIB"standard"
BODY_TYPE"PLUMBING"
HDL_TAP"TRUE";
"B \NAC \NWC"2;
"S \NAC"
BN"5"25;
%"TAP"
"1","(-6225,3125)","0","standard","I3";
;
CDS_LIB"standard"
BODY_TYPE"PLUMBING"
HDL_TAP"TRUE";
"B \NAC \NWC"3;
"S \NAC"
BN"8"19;
%"TAP"
"1","(-1900,5400)","0","standard","I30";
;
CDS_LIB"standard"
BODY_TYPE"PLUMBING"
HDL_TAP"TRUE";
"B \NAC \NWC"2;
"S \NAC"
BN"6"28;
%"TAP"
"1","(-1900,5750)","0","standard","I31";
;
CDS_LIB"standard"
BODY_TYPE"PLUMBING"
HDL_TAP"TRUE";
"B \NAC \NWC"2;
"S \NAC"
BN"7"30;
%"TAP"
"1","(-1700,4600)","0","standard","I32";
;
CDS_LIB"standard"
BODY_TYPE"PLUMBING"
HDL_TAP"TRUE";
"B \NAC \NWC"4;
"S \NAC"
BN"4"12;
%"TAP"
"1","(-1700,4950)","0","standard","I33";
;
CDS_LIB"standard"
BODY_TYPE"PLUMBING"
HDL_TAP"TRUE";
"B \NAC \NWC"4;
"S \NAC"
BN"5"13;
%"TAP"
"1","(-1700,5300)","0","standard","I34";
;
CDS_LIB"standard"
BODY_TYPE"PLUMBING"
HDL_TAP"TRUE";
"B \NAC \NWC"4;
"S \NAC"
BN"6"16;
%"TAP"
"1","(-1700,5650)","0","standard","I35";
;
CDS_LIB"standard"
BODY_TYPE"PLUMBING"
HDL_TAP"TRUE";
"B \NAC \NWC"4;
"S \NAC"
BN"7"14;
%"PT5161LRS"
"7","(-2925,4500)","0","pure_quanta","I38";
;
LOCATION"U6015"
$SEC"7"
CDS_SEC"7"
VALUE"PT5161LRS"
MATERIAL"IC"
PART_TYPE"SMLF"
NEEDS_NO_SIZE"TRUE"
CDS_LMAN_SYM_OUTLINE"-350,1450,300,-1400"
CDS_LIB"pure_quanta"
PART_NUMBER"AJ051610U03";
"A_PETN15"
$PN"EW29"15;
"A_PETP15"
$PN"EU26"26;
"A_PETN14"
$PN"EM29"9;
"A_PETP14"
$PN"EK26"27;
"A_PETN13"
$PN"EE29"10;
"A_PETP13"
$PN"EC26"29;
"A_PETN12"
$PN"DV29"11;
"A_PETP12"
$PN"DT26"23;
"A_PETN11"
$PN"DL29"12;
"A_PETP11"
$PN"DJ26"24;
"A_PETN10"
$PN"DD29"13;
"A_PETP10"
$PN"DB26"25;
"A_PETN9"
$PN"CU29"16;
"A_PETP9"
$PN"CR26"28;
"A_PETN8"
$PN"CK29"14;
"A_PETP8"
$PN"CH26"30;
%"TAP"
"1","(-6425,4275)","0","standard","I4";
;
CDS_LIB"standard"
BODY_TYPE"PLUMBING"
HDL_TAP"TRUE";
"B \NAC \NWC"1;
"S \NAC"
BN"11"34;
%"TAP"
"1","(-6425,3925)","0","standard","I5";
;
CDS_LIB"standard"
BODY_TYPE"PLUMBING"
HDL_TAP"TRUE";
"B \NAC \NWC"1;
"S \NAC"
BN"10"31;
%"TAP"
"1","(-6425,3575)","0","standard","I6";
;
CDS_LIB"standard"
BODY_TYPE"PLUMBING"
HDL_TAP"TRUE";
"B \NAC \NWC"1;
"S \NAC"
BN"9"32;
%"TAP"
"1","(-6225,3475)","0","standard","I7";
;
CDS_LIB"standard"
BODY_TYPE"PLUMBING"
HDL_TAP"TRUE";
"B \NAC \NWC"3;
"S \NAC"
BN"9"20;
%"TAP"
"1","(-6225,3825)","0","standard","I8";
;
CDS_LIB"standard"
BODY_TYPE"PLUMBING"
HDL_TAP"TRUE";
"B \NAC \NWC"3;
"S \NAC"
BN"10"18;
%"TAP"
"1","(-6225,4175)","0","standard","I9";
;
CDS_LIB"standard"
BODY_TYPE"PLUMBING"
HDL_TAP"TRUE";
"B \NAC \NWC"3;
"S \NAC"
BN"11"17;
END.
